(kicad_pcb
	(version 20260206)
	(generator "pcbnew")
	(generator_version "10.0")
	(general
		(thickness 1.6)
		(legacy_teardrops no)
	)
	(paper "A4")
	(title_block
		(title "9054_F0T_PDB_BD_GPU_F_V04_1213_1550_OCP.brd")
		(comment 1 "Grand Teton / footprints 599-602 of 608")
	)
	(layers
		(0 "F.Cu" signal "TOP")
		(4 "In1.Cu" signal "GND")
		(6 "In2.Cu" signal "IN1")
		(8 "In3.Cu" signal "GND1")
		(10 "In4.Cu" signal "VCC")
		(12 "In5.Cu" signal "VCC1")
		(14 "In6.Cu" signal "GND2")
		(16 "In7.Cu" signal "IN2")
		(18 "In8.Cu" signal "GND3")
		(2 "B.Cu" signal "BOTTOM")
		(9 "F.Adhes" user "F.Adhesive")
		(11 "B.Adhes" user "B.Adhesive")
		(13 "F.Paste" user "Package Geometry/Pastemask Top")
		(15 "B.Paste" user "Package Geometry/Pastemask Bottom")
		(5 "F.SilkS" user "Ref Des/Silkscreen Top")
		(7 "B.SilkS" user "Ref Des/Silkscreen Bottom")
		(1 "F.Mask" user "Board Geometry/Soldermask Top")
		(3 "B.Mask" user "Board Geometry/Soldermask Bottom")
		(17 "Dwgs.User" user "User.Drawings")
		(19 "Cmts.User" user "User.Comments")
		(21 "Eco1.User" user "User.Eco1")
		(23 "Eco2.User" user "User.Eco2")
		(25 "Edge.Cuts" user "Board Geometry/Outline")
		(27 "Margin" user)
		(31 "F.CrtYd" user "Package Geometry/Place Bound Top")
		(29 "B.CrtYd" user "Package Geometry/Place Bound Bottom")
		(35 "F.Fab" user "Ref Des/Assembly Top")
		(33 "B.Fab" user "Ref Des/Assembly Bottom")
	)
	(footprint ""
		(layer "B.Cu")
		(at 340.3854 -38.5318 90)
		(property "Reference" "PR6998"
			(at 0 0 90)
			(layer "B.SilkS")
			(hide yes)
			(effects
				(font
					(size 1.27 1.27)
				)
				(justify mirror)
			)
		)
		(property "Value" ""
			(at 0 0 90)
			(layer "B.Fab")
			(effects
				(font
					(size 1.27 1.27)
				)
				(justify mirror)
			)
		)
		(duplicate_pad_numbers_are_jumpers no)
		(fp_line
			(start 0.7874 -0.4064)
			(end -0.7874 -0.4064)
			(stroke
				(width 0.1524)
				(type default)
			)
			(layer "B.SilkS")
		)
		(fp_line
			(start -0.7874 -0.4064)
			(end -0.7874 0.4064)
			(stroke
				(width 0.1524)
				(type default)
			)
			(layer "B.SilkS")
		)
		(fp_line
			(start 0.7874 0.4064)
			(end 0.7874 -0.4064)
			(stroke
				(width 0.1524)
				(type default)
			)
			(layer "B.SilkS")
		)
		(fp_line
			(start -0.7874 0.4064)
			(end 0.7874 0.4064)
			(stroke
				(width 0.1524)
				(type default)
			)
			(layer "B.SilkS")
		)
		(fp_line
			(start 0.67945 -0.305054)
			(end 0.12065 -0.305054)
			(stroke
				(width 0.1)
				(type default)
			)
			(layer "B.Fab")
		)
		(fp_line
			(start 0.12065 -0.305054)
			(end 0.12065 -0.2794)
			(stroke
				(width 0.1)
				(type default)
			)
			(layer "B.Fab")
		)
		(fp_line
			(start -0.12065 -0.3048)
			(end -0.67945 -0.3048)
			(stroke
				(width 0.1)
				(type default)
			)
			(layer "B.Fab")
		)
		(fp_line
			(start -0.67945 -0.3048)
			(end -0.67945 0.3048)
			(stroke
				(width 0.1)
				(type default)
			)
			(layer "B.Fab")
		)
		(fp_line
			(start 0.12065 -0.2794)
			(end -0.12065 -0.2794)
			(stroke
				(width 0.1)
				(type default)
			)
			(layer "B.Fab")
		)
		(fp_line
			(start -0.12065 -0.2794)
			(end -0.12065 -0.3048)
			(stroke
				(width 0.1)
				(type default)
			)
			(layer "B.Fab")
		)
		(fp_line
			(start 0.12065 0.2794)
			(end 0.12065 0.3048)
			(stroke
				(width 0.1)
				(type default)
			)
			(layer "B.Fab")
		)
		(fp_line
			(start -0.120396 0.2794)
			(end 0.12065 0.2794)
			(stroke
				(width 0.1)
				(type default)
			)
			(layer "B.Fab")
		)
		(fp_line
			(start 0.67945 0.3048)
			(end 0.67945 -0.305054)
			(stroke
				(width 0.1)
				(type default)
			)
			(layer "B.Fab")
		)
		(fp_line
			(start 0.12065 0.3048)
			(end 0.67945 0.3048)
			(stroke
				(width 0.1)
				(type default)
			)
			(layer "B.Fab")
		)
		(fp_line
			(start -0.120396 0.3048)
			(end -0.120396 0.2794)
			(stroke
				(width 0.1)
				(type default)
			)
			(layer "B.Fab")
		)
		(fp_line
			(start -0.67945 0.3048)
			(end -0.120396 0.3048)
			(stroke
				(width 0.1)
				(type default)
			)
			(layer "B.Fab")
		)
		(pad "1" smd rect
			(at 0.40005 0 90)
			(size 0.4572 0.508)
			(layers "B.Cu" "B.Mask" "B.Paste")
			(net "P52V_HS1_GATE2_R1")
		)
		(pad "2" smd rect
			(at -0.40005 0 90)
			(size 0.4572 0.508)
			(layers "B.Cu" "B.Mask" "B.Paste")
			(net "P52V_HS1_4287_GATE2_R")
		)
	)
	(footprint ""
		(layer "B.Cu")
		(at 284.2514 -61.849)
		(property "Reference" "PR211"
			(at 0 0 0)
			(layer "B.SilkS")
			(hide yes)
			(effects
				(font
					(size 1.27 1.27)
				)
				(justify mirror)
			)
		)
		(property "Value" ""
			(at 0 0 0)
			(layer "B.Fab")
			(effects
				(font
					(size 1.27 1.27)
				)
				(justify mirror)
			)
		)
		(duplicate_pad_numbers_are_jumpers no)
		(fp_line
			(start -0.7874 -0.4064)
			(end -0.7874 0.4064)
			(stroke
				(width 0.1524)
				(type default)
			)
			(layer "B.SilkS")
		)
		(fp_line
			(start -0.7874 0.4064)
			(end 0.7874 0.4064)
			(stroke
				(width 0.1524)
				(type default)
			)
			(layer "B.SilkS")
		)
		(fp_line
			(start 0.7874 -0.4064)
			(end -0.7874 -0.4064)
			(stroke
				(width 0.1524)
				(type default)
			)
			(layer "B.SilkS")
		)
		(fp_line
			(start 0.7874 0.4064)
			(end 0.7874 -0.4064)
			(stroke
				(width 0.1524)
				(type default)
			)
			(layer "B.SilkS")
		)
		(fp_line
			(start -0.67945 -0.3048)
			(end -0.67945 0.3048)
			(stroke
				(width 0.1)
				(type default)
			)
			(layer "B.Fab")
		)
		(fp_line
			(start -0.67945 0.3048)
			(end -0.120396 0.3048)
			(stroke
				(width 0.1)
				(type default)
			)
			(layer "B.Fab")
		)
		(fp_line
			(start -0.12065 -0.3048)
			(end -0.67945 -0.3048)
			(stroke
				(width 0.1)
				(type default)
			)
			(layer "B.Fab")
		)
		(fp_line
			(start -0.12065 -0.2794)
			(end -0.12065 -0.3048)
			(stroke
				(width 0.1)
				(type default)
			)
			(layer "B.Fab")
		)
		(fp_line
			(start -0.120396 0.2794)
			(end 0.12065 0.2794)
			(stroke
				(width 0.1)
				(type default)
			)
			(layer "B.Fab")
		)
		(fp_line
			(start -0.120396 0.3048)
			(end -0.120396 0.2794)
			(stroke
				(width 0.1)
				(type default)
			)
			(layer "B.Fab")
		)
		(fp_line
			(start 0.12065 -0.305054)
			(end 0.12065 -0.2794)
			(stroke
				(width 0.1)
				(type default)
			)
			(layer "B.Fab")
		)
		(fp_line
			(start 0.12065 -0.2794)
			(end -0.12065 -0.2794)
			(stroke
				(width 0.1)
				(type default)
			)
			(layer "B.Fab")
		)
		(fp_line
			(start 0.12065 0.2794)
			(end 0.12065 0.3048)
			(stroke
				(width 0.1)
				(type default)
			)
			(layer "B.Fab")
		)
		(fp_line
			(start 0.12065 0.3048)
			(end 0.67945 0.3048)
			(stroke
				(width 0.1)
				(type default)
			)
			(layer "B.Fab")
		)
		(fp_line
			(start 0.67945 -0.305054)
			(end 0.12065 -0.305054)
			(stroke
				(width 0.1)
				(type default)
			)
			(layer "B.Fab")
		)
		(fp_line
			(start 0.67945 0.3048)
			(end 0.67945 -0.305054)
			(stroke
				(width 0.1)
				(type default)
			)
			(layer "B.Fab")
		)
		(pad "1" smd circle
			(at 0.40005 0 180)
			(size 0 0)
			(layers "B.Cu" "B.Mask" "B.Paste")
			(net "HS1_TMR2")
		)
		(pad "2" smd circle
			(at -0.40005 0 180)
			(size 0 0)
			(layers "B.Cu" "B.Mask" "B.Paste")
			(net "GND_FIELD_SIGNAL")
		)
	)
	(footprint ""
		(layer "B.Cu")
		(at 278.4094 -64.897)
		(property "Reference" "R145"
			(at 0 0 0)
			(layer "B.SilkS")
			(hide yes)
			(effects
				(font
					(size 1.27 1.27)
				)
				(justify mirror)
			)
		)
		(property "Value" ""
			(at 0 0 0)
			(layer "B.Fab")
			(effects
				(font
					(size 1.27 1.27)
				)
				(justify mirror)
			)
		)
		(duplicate_pad_numbers_are_jumpers no)
		(fp_line
			(start -0.7874 -0.4064)
			(end -0.7874 0.4064)
			(stroke
				(width 0.1524)
				(type default)
			)
			(layer "B.SilkS")
		)
		(fp_line
			(start -0.7874 0.4064)
			(end 0.7874 0.4064)
			(stroke
				(width 0.1524)
				(type default)
			)
			(layer "B.SilkS")
		)
		(fp_line
			(start 0.7874 -0.4064)
			(end -0.7874 -0.4064)
			(stroke
				(width 0.1524)
				(type default)
			)
			(layer "B.SilkS")
		)
		(fp_line
			(start 0.7874 0.4064)
			(end 0.7874 -0.4064)
			(stroke
				(width 0.1524)
				(type default)
			)
			(layer "B.SilkS")
		)
		(fp_line
			(start -0.67945 -0.3048)
			(end -0.67945 0.3048)
			(stroke
				(width 0.1)
				(type default)
			)
			(layer "B.Fab")
		)
		(fp_line
			(start -0.67945 0.3048)
			(end -0.120396 0.3048)
			(stroke
				(width 0.1)
				(type default)
			)
			(layer "B.Fab")
		)
		(fp_line
			(start -0.12065 -0.3048)
			(end -0.67945 -0.3048)
			(stroke
				(width 0.1)
				(type default)
			)
			(layer "B.Fab")
		)
		(fp_line
			(start -0.12065 -0.2794)
			(end -0.12065 -0.3048)
			(stroke
				(width 0.1)
				(type default)
			)
			(layer "B.Fab")
		)
		(fp_line
			(start -0.120396 0.2794)
			(end 0.12065 0.2794)
			(stroke
				(width 0.1)
				(type default)
			)
			(layer "B.Fab")
		)
		(fp_line
			(start -0.120396 0.3048)
			(end -0.120396 0.2794)
			(stroke
				(width 0.1)
				(type default)
			)
			(layer "B.Fab")
		)
		(fp_line
			(start 0.12065 -0.305054)
			(end 0.12065 -0.2794)
			(stroke
				(width 0.1)
				(type default)
			)
			(layer "B.Fab")
		)
		(fp_line
			(start 0.12065 -0.2794)
			(end -0.12065 -0.2794)
			(stroke
				(width 0.1)
				(type default)
			)
			(layer "B.Fab")
		)
		(fp_line
			(start 0.12065 0.2794)
			(end 0.12065 0.3048)
			(stroke
				(width 0.1)
				(type default)
			)
			(layer "B.Fab")
		)
		(fp_line
			(start 0.12065 0.3048)
			(end 0.67945 0.3048)
			(stroke
				(width 0.1)
				(type default)
			)
			(layer "B.Fab")
		)
		(fp_line
			(start 0.67945 -0.305054)
			(end 0.12065 -0.305054)
			(stroke
				(width 0.1)
				(type default)
			)
			(layer "B.Fab")
		)
		(fp_line
			(start 0.67945 0.3048)
			(end 0.67945 -0.305054)
			(stroke
				(width 0.1)
				(type default)
			)
			(layer "B.Fab")
		)
		(pad "1" smd circle
			(at 0.40005 0 180)
			(size 0 0)
			(layers "B.Cu" "B.Mask" "B.Paste")
			(net "SMB_P52V_PDB_SDA")
		)
		(pad "2" smd circle
			(at -0.40005 0 180)
			(size 0 0)
			(layers "B.Cu" "B.Mask" "B.Paste")
			(net "SMB_CM_HS1_3V3SB_DATO")
		)
	)
	(footprint ""
		(layer "B.Cu")
		(at 273.8374 -76.454 -90)
		(property "Reference" "PC586"
			(at 0 0 90)
			(layer "B.SilkS")
			(hide yes)
			(effects
				(font
					(size 1.27 1.27)
				)
				(justify mirror)
			)
		)
		(property "Value" ""
			(at 0 0 90)
			(layer "B.Fab")
			(effects
				(font
					(size 1.27 1.27)
				)
				(justify mirror)
			)
		)
		(duplicate_pad_numbers_are_jumpers no)
		(fp_line
			(start -0.7874 0.4064)
			(end 0.7874 0.4064)
			(stroke
				(width 0.1524)
				(type default)
			)
			(layer "B.SilkS")
		)
		(fp_line
			(start 0.7874 0.4064)
			(end 0.7874 -0.4064)
			(stroke
				(width 0.1524)
				(type default)
			)
			(layer "B.SilkS")
		)
		(fp_line
			(start -0.7874 -0.4064)
			(end -0.7874 0.4064)
			(stroke
				(width 0.1524)
				(type default)
			)
			(layer "B.SilkS")
		)
		(fp_line
			(start 0.7874 -0.4064)
			(end -0.7874 -0.4064)
			(stroke
				(width 0.1524)
				(type default)
			)
			(layer "B.SilkS")
		)
		(fp_line
			(start -0.67945 0.3048)
			(end -0.120396 0.3048)
			(stroke
				(width 0.1)
				(type default)
			)
			(layer "B.Fab")
		)
		(fp_line
			(start -0.120396 0.3048)
			(end -0.120396 0.2794)
			(stroke
				(width 0.1)
				(type default)
			)
			(layer "B.Fab")
		)
		(fp_line
			(start 0.12065 0.3048)
			(end 0.67945 0.3048)
			(stroke
				(width 0.1)
				(type default)
			)
			(layer "B.Fab")
		)
		(fp_line
			(start 0.67945 0.3048)
			(end 0.67945 -0.305054)
			(stroke
				(width 0.1)
				(type default)
			)
			(layer "B.Fab")
		)
		(fp_line
			(start -0.120396 0.2794)
			(end 0.12065 0.2794)
			(stroke
				(width 0.1)
				(type default)
			)
			(layer "B.Fab")
		)
		(fp_line
			(start 0.12065 0.2794)
			(end 0.12065 0.3048)
			(stroke
				(width 0.1)
				(type default)
			)
			(layer "B.Fab")
		)
		(fp_line
			(start -0.12065 -0.2794)
			(end -0.12065 -0.3048)
			(stroke
				(width 0.1)
				(type default)
			)
			(layer "B.Fab")
		)
		(fp_line
			(start 0.12065 -0.2794)
			(end -0.12065 -0.2794)
			(stroke
				(width 0.1)
				(type default)
			)
			(layer "B.Fab")
		)
		(fp_line
			(start -0.67945 -0.3048)
			(end -0.67945 0.3048)
			(stroke
				(width 0.1)
				(type default)
			)
			(layer "B.Fab")
		)
		(fp_line
			(start -0.12065 -0.3048)
			(end -0.67945 -0.3048)
			(stroke
				(width 0.1)
				(type default)
			)
			(layer "B.Fab")
		)
		(fp_line
			(start 0.12065 -0.305054)
			(end 0.12065 -0.2794)
			(stroke
				(width 0.1)
				(type default)
			)
			(layer "B.Fab")
		)
		(fp_line
			(start 0.67945 -0.305054)
			(end 0.12065 -0.305054)
			(stroke
				(width 0.1)
				(type default)
			)
			(layer "B.Fab")
		)
		(pad "1" smd circle
			(at 0.40005 0 90)
			(size 0 0)
			(layers "B.Cu" "B.Mask" "B.Paste")
			(net "P52V_HS1_UVH")
		)
		(pad "2" smd circle
			(at -0.40005 0 90)
			(size 0 0)
			(layers "B.Cu" "B.Mask" "B.Paste")
			(net "GND_FIELD_SIGNAL")
		)
	)
)
